(kicad_pcb
	(version 20260206)
	(generator "pcbnew")
	(generator_version "10.0")
	(general
		(thickness 1.6)
		(legacy_teardrops no)
	)
	(paper "A4")
	(title_block
		(title "03242023_DA0F0TMBIJ0_F0T_Motherboard_J_brd_V01_OCP.brd")
		(comment 1 "Grand Teton / footprints 207-211 of 6105")
	)
	(layers
		(0 "F.Cu" signal "TOP")
		(4 "In1.Cu" signal "GND")
		(6 "In2.Cu" signal "IN1")
		(8 "In3.Cu" signal "GND1")
		(10 "In4.Cu" signal "IN2")
		(12 "In5.Cu" signal "GND2")
		(14 "In6.Cu" signal "IN3")
		(16 "In7.Cu" signal "GND3")
		(18 "In8.Cu" signal "VCC")
		(20 "In9.Cu" signal "VCC1")
		(22 "In10.Cu" signal "GND4")
		(24 "In11.Cu" signal "IN4")
		(26 "In12.Cu" signal "GND5")
		(28 "In13.Cu" signal "IN5")
		(30 "In14.Cu" signal "GND6")
		(32 "In15.Cu" signal "IN6")
		(34 "In16.Cu" signal "GND7")
		(2 "B.Cu" signal "BOTTOM")
		(9 "F.Adhes" user "F.Adhesive")
		(11 "B.Adhes" user "B.Adhesive")
		(13 "F.Paste" user "Package Geometry/Pastemask Top")
		(15 "B.Paste" user "Package Geometry/Pastemask Bottom")
		(5 "F.SilkS" user "Ref Des/Silkscreen Top")
		(7 "B.SilkS" user "Ref Des/Silkscreen Bottom")
		(1 "F.Mask" user "Board Geometry/Soldermask Top")
		(3 "B.Mask" user "Board Geometry/Soldermask Bottom")
		(17 "Dwgs.User" user "User.Drawings")
		(19 "Cmts.User" user "User.Comments")
		(21 "Eco1.User" user "User.Eco1")
		(23 "Eco2.User" user "User.Eco2")
		(25 "Edge.Cuts" user "Board Geometry/Outline")
		(27 "Margin" user)
		(31 "F.CrtYd" user "Package Geometry/Place Bound Top")
		(29 "B.CrtYd" user "Package Geometry/Place Bound Bottom")
		(35 "F.Fab" user "Ref Des/Assembly Top")
		(33 "B.Fab" user "Ref Des/Assembly Bottom")
	)
	(footprint ""
		(layer "F.Cu")
		(at 116.561616 -251.375672 90)
		(property "Reference" "C293"
			(at 0 0 90)
			(layer "F.SilkS")
			(hide yes)
			(effects
				(font
					(size 1.27 1.27)
				)
			)
		)
		(property "Value" ""
			(at 0 0 90)
			(layer "F.Fab")
			(effects
				(font
					(size 1.27 1.27)
				)
			)
		)
		(duplicate_pad_numbers_are_jumpers no)
		(fp_line
			(start 0.7874 -0.4064)
			(end 0.7874 0.4064)
			(stroke
				(width 0.1524)
				(type default)
			)
			(layer "F.SilkS")
		)
		(fp_line
			(start -0.7874 -0.4064)
			(end 0.7874 -0.4064)
			(stroke
				(width 0.1524)
				(type default)
			)
			(layer "F.SilkS")
		)
		(fp_line
			(start 0.7874 0.4064)
			(end -0.7874 0.4064)
			(stroke
				(width 0.1524)
				(type default)
			)
			(layer "F.SilkS")
		)
		(fp_line
			(start -0.7874 0.4064)
			(end -0.7874 -0.4064)
			(stroke
				(width 0.1524)
				(type default)
			)
			(layer "F.SilkS")
		)
		(fp_line
			(start -0.12065 -0.305054)
			(end -0.12065 -0.2794)
			(stroke
				(width 0.1)
				(type default)
			)
			(layer "F.Fab")
		)
		(fp_line
			(start -0.67945 -0.305054)
			(end -0.12065 -0.305054)
			(stroke
				(width 0.1)
				(type default)
			)
			(layer "F.Fab")
		)
		(fp_line
			(start 0.67945 -0.3048)
			(end 0.67945 0.3048)
			(stroke
				(width 0.1)
				(type default)
			)
			(layer "F.Fab")
		)
		(fp_line
			(start 0.12065 -0.3048)
			(end 0.67945 -0.3048)
			(stroke
				(width 0.1)
				(type default)
			)
			(layer "F.Fab")
		)
		(fp_line
			(start 0.12065 -0.2794)
			(end 0.12065 -0.3048)
			(stroke
				(width 0.1)
				(type default)
			)
			(layer "F.Fab")
		)
		(fp_line
			(start -0.12065 -0.2794)
			(end 0.12065 -0.2794)
			(stroke
				(width 0.1)
				(type default)
			)
			(layer "F.Fab")
		)
		(fp_line
			(start 0.120396 0.2794)
			(end -0.12065 0.2794)
			(stroke
				(width 0.1)
				(type default)
			)
			(layer "F.Fab")
		)
		(fp_line
			(start -0.12065 0.2794)
			(end -0.12065 0.3048)
			(stroke
				(width 0.1)
				(type default)
			)
			(layer "F.Fab")
		)
		(fp_line
			(start 0.67945 0.3048)
			(end 0.120396 0.3048)
			(stroke
				(width 0.1)
				(type default)
			)
			(layer "F.Fab")
		)
		(fp_line
			(start 0.120396 0.3048)
			(end 0.120396 0.2794)
			(stroke
				(width 0.1)
				(type default)
			)
			(layer "F.Fab")
		)
		(fp_line
			(start -0.12065 0.3048)
			(end -0.67945 0.3048)
			(stroke
				(width 0.1)
				(type default)
			)
			(layer "F.Fab")
		)
		(fp_line
			(start -0.67945 0.3048)
			(end -0.67945 -0.305054)
			(stroke
				(width 0.1)
				(type default)
			)
			(layer "F.Fab")
		)
		(pad "1" smd circle
			(at -0.40005 0 90)
			(size 0 0)
			(layers "F.Cu" "F.Mask" "F.Paste")
			(net "PVCCIN_CPU1")
		)
		(pad "2" smd circle
			(at 0.40005 0 90)
			(size 0 0)
			(layers "F.Cu" "F.Mask" "F.Paste")
			(net "GND")
		)
	)
	(footprint ""
		(layer "F.Cu")
		(at 268.336522 -394.17117)
		(property "Reference" "PR2530"
			(at 0 0 0)
			(layer "F.SilkS")
			(hide yes)
			(effects
				(font
					(size 1.27 1.27)
				)
			)
		)
		(property "Value" ""
			(at 0 0 0)
			(layer "F.Fab")
			(effects
				(font
					(size 1.27 1.27)
				)
			)
		)
		(duplicate_pad_numbers_are_jumpers no)
		(fp_line
			(start -0.7874 -0.4064)
			(end 0.7874 -0.4064)
			(stroke
				(width 0.1524)
				(type default)
			)
			(layer "F.SilkS")
		)
		(fp_line
			(start -0.7874 0.4064)
			(end -0.7874 -0.4064)
			(stroke
				(width 0.1524)
				(type default)
			)
			(layer "F.SilkS")
		)
		(fp_line
			(start 0.7874 -0.4064)
			(end 0.7874 0.4064)
			(stroke
				(width 0.1524)
				(type default)
			)
			(layer "F.SilkS")
		)
		(fp_line
			(start 0.7874 0.4064)
			(end -0.7874 0.4064)
			(stroke
				(width 0.1524)
				(type default)
			)
			(layer "F.SilkS")
		)
		(fp_line
			(start -0.67945 -0.305054)
			(end -0.12065 -0.305054)
			(stroke
				(width 0.1)
				(type default)
			)
			(layer "F.Fab")
		)
		(fp_line
			(start -0.67945 0.3048)
			(end -0.67945 -0.305054)
			(stroke
				(width 0.1)
				(type default)
			)
			(layer "F.Fab")
		)
		(fp_line
			(start -0.12065 -0.305054)
			(end -0.12065 -0.2794)
			(stroke
				(width 0.1)
				(type default)
			)
			(layer "F.Fab")
		)
		(fp_line
			(start -0.12065 -0.2794)
			(end 0.12065 -0.2794)
			(stroke
				(width 0.1)
				(type default)
			)
			(layer "F.Fab")
		)
		(fp_line
			(start -0.12065 0.2794)
			(end -0.12065 0.3048)
			(stroke
				(width 0.1)
				(type default)
			)
			(layer "F.Fab")
		)
		(fp_line
			(start -0.12065 0.3048)
			(end -0.67945 0.3048)
			(stroke
				(width 0.1)
				(type default)
			)
			(layer "F.Fab")
		)
		(fp_line
			(start 0.120396 0.2794)
			(end -0.12065 0.2794)
			(stroke
				(width 0.1)
				(type default)
			)
			(layer "F.Fab")
		)
		(fp_line
			(start 0.120396 0.3048)
			(end 0.120396 0.2794)
			(stroke
				(width 0.1)
				(type default)
			)
			(layer "F.Fab")
		)
		(fp_line
			(start 0.12065 -0.3048)
			(end 0.67945 -0.3048)
			(stroke
				(width 0.1)
				(type default)
			)
			(layer "F.Fab")
		)
		(fp_line
			(start 0.12065 -0.2794)
			(end 0.12065 -0.3048)
			(stroke
				(width 0.1)
				(type default)
			)
			(layer "F.Fab")
		)
		(fp_line
			(start 0.67945 -0.3048)
			(end 0.67945 0.3048)
			(stroke
				(width 0.1)
				(type default)
			)
			(layer "F.Fab")
		)
		(fp_line
			(start 0.67945 0.3048)
			(end 0.120396 0.3048)
			(stroke
				(width 0.1)
				(type default)
			)
			(layer "F.Fab")
		)
		(pad "1" smd circle
			(at -0.40005 0)
			(size 0 0)
			(layers "F.Cu" "F.Mask" "F.Paste")
			(net "P12V_HSC_GATE_G3")
		)
		(pad "2" smd circle
			(at 0.40005 0)
			(size 0 0)
			(layers "F.Cu" "F.Mask" "F.Paste")
			(net "P12V_HSC_GATE2")
		)
	)
	(footprint ""
		(layer "F.Cu")
		(at 363.556042 -397.959834)
		(property "Reference" "U176"
			(at -0.112522 -2.236724 0)
			(unlocked yes)
			(layer "F.SilkS")
			(effects
				(font
					(size 0.7874 0.5842)
					(thickness 0.1524)
				)
				(justify left)
			)
		)
		(property "Value" ""
			(at 0 0 0)
			(layer "F.Fab")
			(effects
				(font
					(size 1.27 1.27)
				)
			)
		)
		(duplicate_pad_numbers_are_jumpers no)
		(fp_line
			(start -1.3716 -1.524)
			(end -0.508 -1.524)
			(stroke
				(width 0.1524)
				(type default)
			)
			(layer "F.SilkS")
		)
		(fp_line
			(start -1.3716 1.524)
			(end -1.3716 -1.524)
			(stroke
				(width 0.1524)
				(type default)
			)
			(layer "F.SilkS")
		)
		(fp_line
			(start -0.508 -1.524)
			(end 0 -1.016)
			(stroke
				(width 0.1524)
				(type default)
			)
			(layer "F.SilkS")
		)
		(fp_line
			(start 0 -1.016)
			(end 0.508 -1.524)
			(stroke
				(width 0.1524)
				(type default)
			)
			(layer "F.SilkS")
		)
		(fp_line
			(start 0.508 -1.524)
			(end 1.3716 -1.524)
			(stroke
				(width 0.1524)
				(type default)
			)
			(layer "F.SilkS")
		)
		(fp_line
			(start 1.3716 -1.524)
			(end 1.3716 1.524)
			(stroke
				(width 0.1524)
				(type default)
			)
			(layer "F.SilkS")
		)
		(fp_line
			(start 1.3716 1.524)
			(end -1.3716 1.524)
			(stroke
				(width 0.1524)
				(type default)
			)
			(layer "F.SilkS")
		)
		(fp_poly
			(pts
				(xy -1.457452 -2.04724) (xy -1.78562 -1.49352) (xy -2.082292 -2.04724)
			)
			(stroke
				(width 0)
				(type default)
			)
			(fill yes)
			(layer "F.SilkS")
		)
		(fp_line
			(start -2.54 -1.0668)
			(end -1.5494 -1.0668)
			(stroke
				(width 0.1)
				(type default)
			)
			(layer "F.Fab")
		)
		(fp_line
			(start -2.54 1.0668)
			(end -2.54 -1.0668)
			(stroke
				(width 0.1)
				(type default)
			)
			(layer "F.Fab")
		)
		(fp_line
			(start -1.5494 -1.524)
			(end 1.5494 -1.524)
			(stroke
				(width 0.1)
				(type default)
			)
			(layer "F.Fab")
		)
		(fp_line
			(start -1.5494 -1.0668)
			(end -1.5494 -1.524)
			(stroke
				(width 0.1)
				(type default)
			)
			(layer "F.Fab")
		)
		(fp_line
			(start -1.5494 1.0668)
			(end -2.54 1.0668)
			(stroke
				(width 0.1)
				(type default)
			)
			(layer "F.Fab")
		)
		(fp_line
			(start -1.5494 1.0668)
			(end -1.5494 -1.0668)
			(stroke
				(width 0.1)
				(type default)
			)
			(layer "F.Fab")
		)
		(fp_line
			(start -1.5494 1.524)
			(end -1.5494 1.0668)
			(stroke
				(width 0.1)
				(type default)
			)
			(layer "F.Fab")
		)
		(fp_line
			(start 1.5494 -1.524)
			(end 1.5494 -1.0668)
			(stroke
				(width 0.1)
				(type default)
			)
			(layer "F.Fab")
		)
		(fp_line
			(start 1.5494 -1.0668)
			(end 1.5494 1.0668)
			(stroke
				(width 0.1)
				(type default)
			)
			(layer "F.Fab")
		)
		(fp_line
			(start 1.5494 -1.0668)
			(end 2.54 -1.0668)
			(stroke
				(width 0.1)
				(type default)
			)
			(layer "F.Fab")
		)
		(fp_line
			(start 1.5494 1.0668)
			(end 1.5494 1.524)
			(stroke
				(width 0.1)
				(type default)
			)
			(layer "F.Fab")
		)
		(fp_line
			(start 1.5494 1.524)
			(end -1.5494 1.524)
			(stroke
				(width 0.1)
				(type default)
			)
			(layer "F.Fab")
		)
		(fp_line
			(start 2.54 -1.0668)
			(end 2.54 1.0668)
			(stroke
				(width 0.1)
				(type default)
			)
			(layer "F.Fab")
		)
		(fp_line
			(start 2.54 1.0668)
			(end 1.5494 1.0668)
			(stroke
				(width 0.1)
				(type default)
			)
			(layer "F.Fab")
		)
		(fp_poly
			(pts
				(xy -3.60172 -0.719328) (xy -3.60172 -1.344168) (xy -3.048 -1.016)
			)
			(stroke
				(width 0)
				(type default)
			)
			(fill yes)
			(layer "F.Fab")
		)
		(pad "1" smd rect
			(at -2.232406 -0.975106 270)
			(size 0.3556 1.4224)
			(layers "F.Cu" "F.Mask" "F.Paste")
			(net "SMB_BMC_SWB_EN_R2")
		)
		(pad "2" smd rect
			(at -2.232406 -0.32512 270)
			(size 0.3556 1.4224)
			(layers "F.Cu" "F.Mask" "F.Paste")
			(net "I3C_BMC_SWB_BUF_R_SCL")
		)
		(pad "3" smd rect
			(at -2.232406 0.32512 270)
			(size 0.3556 1.4224)
			(layers "F.Cu" "F.Mask" "F.Paste")
			(net "I3C_BMC_SWB_R_SCL")
		)
		(pad "4" smd rect
			(at -2.232406 0.975106 270)
			(size 0.3556 1.4224)
			(layers "F.Cu" "F.Mask" "F.Paste")
			(net "GND")
		)
		(pad "5" smd rect
			(at 2.232406 0.975106 270)
			(size 0.3556 1.4224)
			(layers "F.Cu" "F.Mask" "F.Paste")
			(net "Net_8615")
		)
		(pad "6" smd rect
			(at 2.232406 0.32512 270)
			(size 0.3556 1.4224)
			(layers "F.Cu" "F.Mask" "F.Paste")
			(net "I3C_BMC_SWB_R_SDA")
		)
		(pad "7" smd rect
			(at 2.232406 -0.32512 270)
			(size 0.3556 1.4224)
			(layers "F.Cu" "F.Mask" "F.Paste")
			(net "I3C_BMC_SWB_BUF_R_SDA")
		)
		(pad "8" smd rect
			(at 2.232406 -0.975106 270)
			(size 0.3556 1.4224)
			(layers "F.Cu" "F.Mask" "F.Paste")
			(net "P3V3_AUX")
		)
	)
	(footprint ""
		(layer "F.Cu")
		(at 49.962054 -358.691942)
		(property "Reference" "PR224"
			(at 0 0 0)
			(layer "F.SilkS")
			(hide yes)
			(effects
				(font
					(size 1.27 1.27)
				)
			)
		)
		(property "Value" ""
			(at 0 0 0)
			(layer "F.Fab")
			(effects
				(font
					(size 1.27 1.27)
				)
			)
		)
		(duplicate_pad_numbers_are_jumpers no)
		(fp_line
			(start -0.7874 -0.4064)
			(end 0.7874 -0.4064)
			(stroke
				(width 0.1524)
				(type default)
			)
			(layer "F.SilkS")
		)
		(fp_line
			(start -0.7874 0.4064)
			(end -0.7874 -0.4064)
			(stroke
				(width 0.1524)
				(type default)
			)
			(layer "F.SilkS")
		)
		(fp_line
			(start 0.7874 -0.4064)
			(end 0.7874 0.4064)
			(stroke
				(width 0.1524)
				(type default)
			)
			(layer "F.SilkS")
		)
		(fp_line
			(start 0.7874 0.4064)
			(end -0.7874 0.4064)
			(stroke
				(width 0.1524)
				(type default)
			)
			(layer "F.SilkS")
		)
		(fp_line
			(start -0.67945 -0.305054)
			(end -0.12065 -0.305054)
			(stroke
				(width 0.1)
				(type default)
			)
			(layer "F.Fab")
		)
		(fp_line
			(start -0.67945 0.3048)
			(end -0.67945 -0.305054)
			(stroke
				(width 0.1)
				(type default)
			)
			(layer "F.Fab")
		)
		(fp_line
			(start -0.12065 -0.305054)
			(end -0.12065 -0.2794)
			(stroke
				(width 0.1)
				(type default)
			)
			(layer "F.Fab")
		)
		(fp_line
			(start -0.12065 -0.2794)
			(end 0.12065 -0.2794)
			(stroke
				(width 0.1)
				(type default)
			)
			(layer "F.Fab")
		)
		(fp_line
			(start -0.12065 0.2794)
			(end -0.12065 0.3048)
			(stroke
				(width 0.1)
				(type default)
			)
			(layer "F.Fab")
		)
		(fp_line
			(start -0.12065 0.3048)
			(end -0.67945 0.3048)
			(stroke
				(width 0.1)
				(type default)
			)
			(layer "F.Fab")
		)
		(fp_line
			(start 0.120396 0.2794)
			(end -0.12065 0.2794)
			(stroke
				(width 0.1)
				(type default)
			)
			(layer "F.Fab")
		)
		(fp_line
			(start 0.120396 0.3048)
			(end 0.120396 0.2794)
			(stroke
				(width 0.1)
				(type default)
			)
			(layer "F.Fab")
		)
		(fp_line
			(start 0.12065 -0.3048)
			(end 0.67945 -0.3048)
			(stroke
				(width 0.1)
				(type default)
			)
			(layer "F.Fab")
		)
		(fp_line
			(start 0.12065 -0.2794)
			(end 0.12065 -0.3048)
			(stroke
				(width 0.1)
				(type default)
			)
			(layer "F.Fab")
		)
		(fp_line
			(start 0.67945 -0.3048)
			(end 0.67945 0.3048)
			(stroke
				(width 0.1)
				(type default)
			)
			(layer "F.Fab")
		)
		(fp_line
			(start 0.67945 0.3048)
			(end 0.120396 0.3048)
			(stroke
				(width 0.1)
				(type default)
			)
			(layer "F.Fab")
		)
		(pad "1" smd circle
			(at -0.40005 0)
			(size 0 0)
			(layers "F.Cu" "F.Mask" "F.Paste")
			(net "PVCCFA_EHV_FIVRA_CPU1_LSET2")
		)
		(pad "2" smd circle
			(at 0.40005 0)
			(size 0 0)
			(layers "F.Cu" "F.Mask" "F.Paste")
			(net "GND")
		)
	)
	(footprint ""
		(layer "F.Cu")
		(at 407.86812 -166.253668)
		(property "Reference" "PC639"
			(at 0 0 0)
			(layer "F.SilkS")
			(hide yes)
			(effects
				(font
					(size 1.27 1.27)
				)
			)
		)
		(property "Value" ""
			(at 0 0 0)
			(layer "F.Fab")
			(effects
				(font
					(size 1.27 1.27)
				)
			)
		)
		(duplicate_pad_numbers_are_jumpers no)
		(fp_line
			(start -0.7874 -0.4064)
			(end 0.7874 -0.4064)
			(stroke
				(width 0.1524)
				(type default)
			)
			(layer "F.SilkS")
		)
		(fp_line
			(start -0.7874 0.4064)
			(end -0.7874 -0.4064)
			(stroke
				(width 0.1524)
				(type default)
			)
			(layer "F.SilkS")
		)
		(fp_line
			(start 0.7874 -0.4064)
			(end 0.7874 0.4064)
			(stroke
				(width 0.1524)
				(type default)
			)
			(layer "F.SilkS")
		)
		(fp_line
			(start 0.7874 0.4064)
			(end -0.7874 0.4064)
			(stroke
				(width 0.1524)
				(type default)
			)
			(layer "F.SilkS")
		)
		(fp_line
			(start -0.67945 -0.305054)
			(end -0.12065 -0.305054)
			(stroke
				(width 0.1)
				(type default)
			)
			(layer "F.Fab")
		)
		(fp_line
			(start -0.67945 0.3048)
			(end -0.67945 -0.305054)
			(stroke
				(width 0.1)
				(type default)
			)
			(layer "F.Fab")
		)
		(fp_line
			(start -0.12065 -0.305054)
			(end -0.12065 -0.2794)
			(stroke
				(width 0.1)
				(type default)
			)
			(layer "F.Fab")
		)
		(fp_line
			(start -0.12065 -0.2794)
			(end 0.12065 -0.2794)
			(stroke
				(width 0.1)
				(type default)
			)
			(layer "F.Fab")
		)
		(fp_line
			(start -0.12065 0.2794)
			(end -0.12065 0.3048)
			(stroke
				(width 0.1)
				(type default)
			)
			(layer "F.Fab")
		)
		(fp_line
			(start -0.12065 0.3048)
			(end -0.67945 0.3048)
			(stroke
				(width 0.1)
				(type default)
			)
			(layer "F.Fab")
		)
		(fp_line
			(start 0.120396 0.2794)
			(end -0.12065 0.2794)
			(stroke
				(width 0.1)
				(type default)
			)
			(layer "F.Fab")
		)
		(fp_line
			(start 0.120396 0.3048)
			(end 0.120396 0.2794)
			(stroke
				(width 0.1)
				(type default)
			)
			(layer "F.Fab")
		)
		(fp_line
			(start 0.12065 -0.3048)
			(end 0.67945 -0.3048)
			(stroke
				(width 0.1)
				(type default)
			)
			(layer "F.Fab")
		)
		(fp_line
			(start 0.12065 -0.2794)
			(end 0.12065 -0.3048)
			(stroke
				(width 0.1)
				(type default)
			)
			(layer "F.Fab")
		)
		(fp_line
			(start 0.67945 -0.3048)
			(end 0.67945 0.3048)
			(stroke
				(width 0.1)
				(type default)
			)
			(layer "F.Fab")
		)
		(fp_line
			(start 0.67945 0.3048)
			(end 0.120396 0.3048)
			(stroke
				(width 0.1)
				(type default)
			)
			(layer "F.Fab")
		)
		(pad "1" smd circle
			(at -0.40005 0)
			(size 0 0)
			(layers "F.Cu" "F.Mask" "F.Paste")
			(net "PVCCD_HV_CPU0")
		)
		(pad "2" smd circle
			(at 0.40005 0)
			(size 0 0)
			(layers "F.Cu" "F.Mask" "F.Paste")
			(net "GND")
		)
	)
)
